(kicad_pcb
	(version 20241229)
	(generator "pcbnew")
	(generator_version "9.0")
	(general
		(thickness 1.62)
		(legacy_teardrops no)
	)
	(paper "A3")
	(title_block
		(title "COM Express 7 Baseboard")
		(date "2025-02-04")
		(rev "1.1.2")
		(company "Antmicro Ltd")
		(comment 1 "www.antmicro.com")
		(comment 9 "footprints 642-646 of 802")
	)
	(layers
		(0 "F.Cu" signal)
		(4 "In1.Cu" signal)
		(6 "In2.Cu" signal)
		(8 "In3.Cu" signal)
		(10 "In4.Cu" signal)
		(12 "In5.Cu" signal)
		(14 "In6.Cu" signal)
		(2 "B.Cu" signal)
		(9 "F.Adhes" user "F.Adhesive")
		(11 "B.Adhes" user "B.Adhesive")
		(13 "F.Paste" user)
		(15 "B.Paste" user)
		(5 "F.SilkS" user "F.Silkscreen")
		(7 "B.SilkS" user "B.Silkscreen")
		(1 "F.Mask" user)
		(3 "B.Mask" user)
		(17 "Dwgs.User" user "User.Drawings")
		(19 "Cmts.User" user "User.Comments")
		(21 "Eco1.User" user "User.Eco1")
		(23 "Eco2.User" user "User.Eco2")
		(25 "Edge.Cuts" user)
		(27 "Margin" user)
		(31 "F.CrtYd" user "F.Courtyard")
		(29 "B.CrtYd" user "B.Courtyard")
		(35 "F.Fab" user)
		(33 "B.Fab" user)
	)
	(footprint "antmicro-footprints:C_0402_1005Metric"
		(layer "B.Cu")
		(at 141.9 138.01)
		(descr "Capacitor SMD 0402")
		(tags "capacitor SMD 0402")
		(property "Reference" "C148"
			(at -1.25 1.4 0)
			(layer "B.SilkS")
			(effects
				(font
					(size 0.7 0.7)
					(thickness 0.15)
				)
				(justify right bottom mirror)
			)
		)
		(property "Value" "C_100n_0402"
			(at -1.022927 -2.155213 0)
			(layer "B.Fab")
			(effects
				(font
					(size 0.7 0.7)
					(thickness 0.15)
				)
				(justify right bottom mirror)
			)
		)
		(property "Datasheet" "https://www.murata.com/products/productdetail?partno=GRM155R61H104KE14%23"
			(at 0 0 0)
			(layer "F.Fab")
			(hide yes)
			(effects
				(font
					(size 1.27 1.27)
					(thickness 0.15)
				)
			)
		)
		(property "Author" "Antmicro"
			(at 0 0 0)
			(layer "B.Fab")
			(hide yes)
			(effects
				(font
					(size 1 1)
					(thickness 0.15)
				)
				(justify mirror)
			)
		)
		(property "Dielectric" "X5R"
			(at 0 0 0)
			(layer "B.Fab")
			(hide yes)
			(effects
				(font
					(size 1 1)
					(thickness 0.15)
				)
				(justify mirror)
			)
		)
		(property "License" "Apache-2.0"
			(at 0 0 0)
			(layer "B.Fab")
			(hide yes)
			(effects
				(font
					(size 1 1)
					(thickness 0.15)
				)
				(justify mirror)
			)
		)
		(property "MPN" "GRM155R61H104KE14D"
			(at 0 0 0)
			(layer "B.Fab")
			(hide yes)
			(effects
				(font
					(size 1 1)
					(thickness 0.15)
				)
				(justify mirror)
			)
		)
		(property "Manufacturer" "Murata"
			(at 0 0 0)
			(layer "B.Fab")
			(hide yes)
			(effects
				(font
					(size 1 1)
					(thickness 0.15)
				)
				(justify mirror)
			)
		)
		(property "Public" "False"
			(at 0 0 0)
			(layer "B.Fab")
			(hide yes)
			(effects
				(font
					(size 1 1)
					(thickness 0.15)
				)
				(justify mirror)
			)
		)
		(property "Val" "100n"
			(at 0 0 0)
			(layer "B.Fab")
			(hide yes)
			(effects
				(font
					(size 1 1)
					(thickness 0.15)
				)
				(justify mirror)
			)
		)
		(property "Voltage" "50V"
			(at 0 0 0)
			(layer "B.Fab")
			(hide yes)
			(effects
				(font
					(size 1 1)
					(thickness 0.15)
				)
				(justify mirror)
			)
		)
		(sheetname "KR to SFI #1")
		(sheetfile "kr_sfi.kicad_sch")
		(attr smd)
		(fp_rect
			(start -0.925 0.47)
			(end 0.925 -0.47)
			(stroke
				(width 0.05)
				(type default)
			)
			(fill no)
			(layer "B.CrtYd")
		)
		(fp_line
			(start -0.494 -0.248)
			(end 0.504 -0.248)
			(stroke
				(width 0.15)
				(type solid)
			)
			(layer "B.Fab")
		)
		(fp_line
			(start -0.494 0.25)
			(end -0.494 -0.248)
			(stroke
				(width 0.15)
				(type solid)
			)
			(layer "B.Fab")
		)
		(fp_line
			(start 0.504 -0.248)
			(end 0.504 0.25)
			(stroke
				(width 0.15)
				(type solid)
			)
			(layer "B.Fab")
		)
		(fp_line
			(start 0.504 0.25)
			(end -0.494 0.25)
			(stroke
				(width 0.15)
				(type solid)
			)
			(layer "B.Fab")
		)
		(pad "1" smd roundrect
			(at -0.48 0)
			(size 0.59 0.64)
			(layers "B.Cu" "B.Mask" "B.Paste")
			(roundrect_rratio 0.25)
			(net 1 "GND")
			(pintype "passive")
			(teardrops
				(best_length_ratio 0.2)
				(max_length 1)
				(best_width_ratio 0.9)
				(max_width 2)
				(curved_edges yes)
				(filter_ratio 0.9)
				(enabled yes)
				(allow_two_segments yes)
				(prefer_zone_connections yes)
			)
		)
		(pad "2" smd roundrect
			(at 0.48 0)
			(size 0.59 0.64)
			(layers "B.Cu" "B.Mask" "B.Paste")
			(roundrect_rratio 0.25)
			(net 2 "+3V3")
			(pintype "passive")
			(teardrops
				(best_length_ratio 0.2)
				(max_length 1)
				(best_width_ratio 0.9)
				(max_width 2)
				(curved_edges yes)
				(filter_ratio 0.9)
				(enabled yes)
				(allow_two_segments yes)
				(prefer_zone_connections yes)
			)
		)
	)
	(footprint "antmicro-footprints:R_0402_1005Metric"
		(layer "B.Cu")
		(at 139.74 142.36 180)
		(descr "Resistor SMD 0402")
		(tags "resistor SMD 0402")
		(property "Reference" "R295"
			(at 0.79 -0.7 0)
			(layer "B.SilkS")
			(effects
				(font
					(size 0.7 0.7)
					(thickness 0.15)
				)
				(justify left bottom mirror)
			)
		)
		(property "Value" "R_10k_0402"
			(at -1.011843 -1.772047 0)
			(layer "B.Fab")
			(effects
				(font
					(size 0.7 0.7)
					(thickness 0.15)
				)
				(justify left bottom mirror)
			)
		)
		(property "Datasheet" "https://www.bourns.com/docs/product-datasheets/cr.pdf"
			(at 0 0 180)
			(layer "F.Fab")
			(hide yes)
			(effects
				(font
					(size 1.27 1.27)
					(thickness 0.15)
				)
			)
		)
		(property "Author" "Antmicro"
			(at 279.48 284.72 0)
			(layer "B.Fab")
			(hide yes)
			(effects
				(font
					(size 1 1)
					(thickness 0.15)
				)
				(justify mirror)
			)
		)
		(property "License" "Apache-2.0"
			(at 279.48 284.72 0)
			(layer "B.Fab")
			(hide yes)
			(effects
				(font
					(size 1 1)
					(thickness 0.15)
				)
				(justify mirror)
			)
		)
		(property "MPN" "CR0402-FX-1002GLF"
			(at 279.48 284.72 0)
			(layer "B.Fab")
			(hide yes)
			(effects
				(font
					(size 1 1)
					(thickness 0.15)
				)
				(justify mirror)
			)
		)
		(property "Manufacturer" "Bourns"
			(at 279.48 284.72 0)
			(layer "B.Fab")
			(hide yes)
			(effects
				(font
					(size 1 1)
					(thickness 0.15)
				)
				(justify mirror)
			)
		)
		(property "Public" "False"
			(at 279.48 284.72 0)
			(layer "B.Fab")
			(hide yes)
			(effects
				(font
					(size 1 1)
					(thickness 0.15)
				)
				(justify mirror)
			)
		)
		(property "Tolerance" "1%"
			(at 279.48 284.72 0)
			(layer "B.Fab")
			(hide yes)
			(effects
				(font
					(size 1 1)
					(thickness 0.15)
				)
				(justify mirror)
			)
		)
		(property "Val" "10k"
			(at 279.48 284.72 0)
			(layer "B.Fab")
			(hide yes)
			(effects
				(font
					(size 1 1)
					(thickness 0.15)
				)
				(justify mirror)
			)
		)
		(sheetname "KR to SFI #2")
		(sheetfile "kr_sfi.kicad_sch")
		(attr smd)
		(fp_rect
			(start -0.925 0.47)
			(end 0.925 -0.47)
			(stroke
				(width 0.05)
				(type default)
			)
			(fill no)
			(layer "B.CrtYd")
		)
		(fp_rect
			(start -0.5 0.25)
			(end 0.5 -0.25)
			(stroke
				(width 0.15)
				(type solid)
			)
			(fill no)
			(layer "B.Fab")
		)
		(pad "1" smd roundrect
			(at -0.48 0 180)
			(size 0.59 0.64)
			(layers "B.Cu" "B.Mask" "B.Paste")
			(roundrect_rratio 0.25)
			(net 1 "GND")
			(pintype "passive")
			(teardrops
				(best_length_ratio 0.2)
				(max_length 1)
				(best_width_ratio 0.9)
				(max_width 2)
				(curved_edges yes)
				(filter_ratio 0.9)
				(enabled yes)
				(allow_two_segments yes)
				(prefer_zone_connections yes)
			)
		)
		(pad "2" smd roundrect
			(at 0.48 0 180)
			(size 0.59 0.64)
			(layers "B.Cu" "B.Mask" "B.Paste")
			(roundrect_rratio 0.25)
			(net 676 "Net-(U45C-PRTAD0)")
			(pintype "passive")
			(teardrops
				(best_length_ratio 0.2)
				(max_length 1)
				(best_width_ratio 0.9)
				(max_width 2)
				(curved_edges yes)
				(filter_ratio 0.9)
				(enabled yes)
				(allow_two_segments yes)
				(prefer_zone_connections yes)
			)
		)
	)
	(footprint "antmicro-footprints:TP_SMD_0.75mm"
		(layer "B.Cu")
		(at 224.4 165.25)
		(property "Reference" "TP38"
			(at -0.499999 -0.45 90)
			(layer "B.SilkS")
			(effects
				(font
					(size 0.7 0.7)
					(thickness 0.15)
				)
				(justify right top mirror)
			)
		)
		(property "Value" "TP_0.75mm_SMD"
			(at 0 -1.2 0)
			(layer "B.Fab")
			(effects
				(font
					(size 0.7 0.7)
					(thickness 0.15)
				)
				(justify right top mirror)
			)
		)
		(property "Author" "Antmicro"
			(at 361.8 295.32 0)
			(layer "B.Fab")
			(hide yes)
			(effects
				(font
					(size 1 1)
					(thickness 0.15)
				)
				(justify mirror)
			)
		)
		(property "License" "Apache-2.0"
			(at 361.8 295.32 0)
			(layer "B.Fab")
			(hide yes)
			(effects
				(font
					(size 1 1)
					(thickness 0.15)
				)
				(justify mirror)
			)
		)
		(property "MPN" ""
			(at 361.8 295.32 0)
			(layer "B.Fab")
			(hide yes)
			(effects
				(font
					(size 1 1)
					(thickness 0.15)
				)
				(justify mirror)
			)
		)
		(property "Manufacturer" ""
			(at 361.8 295.32 0)
			(layer "B.Fab")
			(hide yes)
			(effects
				(font
					(size 1 1)
					(thickness 0.15)
				)
				(justify mirror)
			)
		)
		(property "Public" "False"
			(at 361.8 295.32 0)
			(layer "B.Fab")
			(hide yes)
			(effects
				(font
					(size 1 1)
					(thickness 0.15)
				)
				(justify mirror)
			)
		)
		(sheetname "Com Express 7 MGMT")
		(sheetfile "com_express_7_mgmt.kicad_sch")
		(attr exclude_from_pos_files exclude_from_bom)
		(fp_circle
			(center 0 0)
			(end 0.475 0)
			(stroke
				(width 0.05)
				(type default)
			)
			(fill no)
			(layer "B.CrtYd")
		)
		(pad "1" smd circle
			(at 0 0)
			(size 0.75 0.75)
			(layers "B.Cu" "B.Mask")
			(net 343 "Net-(J12D-~{TYPE10})")
			(pinfunction "1")
			(pintype "passive")
			(teardrops
				(best_length_ratio 0.4)
				(max_length 1)
				(best_width_ratio 0.9)
				(max_width 2)
				(curved_edges yes)
				(filter_ratio 0.9)
				(enabled yes)
				(allow_two_segments yes)
				(prefer_zone_connections yes)
			)
		)
	)
	(footprint "antmicro-footprints:C_0402_1005Metric"
		(layer "B.Cu")
		(at 133.79 134.86 180)
		(descr "Capacitor SMD 0402")
		(tags "capacitor SMD 0402")
		(property "Reference" "C184"
			(at -3.61 -0.45 0)
			(layer "B.SilkS")
			(effects
				(font
					(size 0.7 0.7)
					(thickness 0.15)
				)
				(justify left bottom mirror)
			)
		)
		(property "Value" "C_100n_0402"
			(at -1.022927 -2.155213 0)
			(layer "B.Fab")
			(effects
				(font
					(size 0.7 0.7)
					(thickness 0.15)
				)
				(justify left bottom mirror)
			)
		)
		(property "Datasheet" "https://www.murata.com/products/productdetail?partno=GRM155R61H104KE14%23"
			(at 0 0 180)
			(layer "F.Fab")
			(hide yes)
			(effects
				(font
					(size 1.27 1.27)
					(thickness 0.15)
				)
			)
		)
		(property "Author" "Antmicro"
			(at 267.58 269.72 0)
			(layer "B.Fab")
			(hide yes)
			(effects
				(font
					(size 1 1)
					(thickness 0.15)
				)
				(justify mirror)
			)
		)
		(property "Dielectric" "X5R"
			(at 267.58 269.72 0)
			(layer "B.Fab")
			(hide yes)
			(effects
				(font
					(size 1 1)
					(thickness 0.15)
				)
				(justify mirror)
			)
		)
		(property "License" "Apache-2.0"
			(at 267.58 269.72 0)
			(layer "B.Fab")
			(hide yes)
			(effects
				(font
					(size 1 1)
					(thickness 0.15)
				)
				(justify mirror)
			)
		)
		(property "MPN" "GRM155R61H104KE14D"
			(at 267.58 269.72 0)
			(layer "B.Fab")
			(hide yes)
			(effects
				(font
					(size 1 1)
					(thickness 0.15)
				)
				(justify mirror)
			)
		)
		(property "Manufacturer" "Murata"
			(at 267.58 269.72 0)
			(layer "B.Fab")
			(hide yes)
			(effects
				(font
					(size 1 1)
					(thickness 0.15)
				)
				(justify mirror)
			)
		)
		(property "Public" "False"
			(at 267.58 269.72 0)
			(layer "B.Fab")
			(hide yes)
			(effects
				(font
					(size 1 1)
					(thickness 0.15)
				)
				(justify mirror)
			)
		)
		(property "Val" "100n"
			(at 267.58 269.72 0)
			(layer "B.Fab")
			(hide yes)
			(effects
				(font
					(size 1 1)
					(thickness 0.15)
				)
				(justify mirror)
			)
		)
		(property "Voltage" "50V"
			(at 267.58 269.72 0)
			(layer "B.Fab")
			(hide yes)
			(effects
				(font
					(size 1 1)
					(thickness 0.15)
				)
				(justify mirror)
			)
		)
		(sheetname "KR to SFI #2")
		(sheetfile "kr_sfi.kicad_sch")
		(attr smd)
		(fp_rect
			(start -0.925 0.47)
			(end 0.925 -0.47)
			(stroke
				(width 0.05)
				(type default)
			)
			(fill no)
			(layer "B.CrtYd")
		)
		(fp_line
			(start 0.504 0.25)
			(end -0.494 0.25)
			(stroke
				(width 0.15)
				(type solid)
			)
			(layer "B.Fab")
		)
		(fp_line
			(start 0.504 -0.248)
			(end 0.504 0.25)
			(stroke
				(width 0.15)
				(type solid)
			)
			(layer "B.Fab")
		)
		(fp_line
			(start -0.494 0.25)
			(end -0.494 -0.248)
			(stroke
				(width 0.15)
				(type solid)
			)
			(layer "B.Fab")
		)
		(fp_line
			(start -0.494 -0.248)
			(end 0.504 -0.248)
			(stroke
				(width 0.15)
				(type solid)
			)
			(layer "B.Fab")
		)
		(pad "1" smd roundrect
			(at -0.48 0 180)
			(size 0.59 0.64)
			(layers "B.Cu" "B.Mask" "B.Paste")
			(roundrect_rratio 0.25)
			(net 1 "GND")
			(pintype "passive")
			(teardrops
				(best_length_ratio 0.2)
				(max_length 1)
				(best_width_ratio 0.9)
				(max_width 2)
				(curved_edges yes)
				(filter_ratio 0.9)
				(enabled yes)
				(allow_two_segments yes)
				(prefer_zone_connections yes)
			)
		)
		(pad "2" smd roundrect
			(at 0.48 0 180)
			(size 0.59 0.64)
			(layers "B.Cu" "B.Mask" "B.Paste")
			(roundrect_rratio 0.25)
			(net 74 "+1V0")
			(pintype "passive")
			(teardrops
				(best_length_ratio 0.2)
				(max_length 1)
				(best_width_ratio 0.9)
				(max_width 2)
				(curved_edges yes)
				(filter_ratio 0.9)
				(enabled yes)
				(allow_two_segments yes)
				(prefer_zone_connections yes)
			)
		)
	)
	(footprint "antmicro-footprints:C_0402_1005Metric"
		(layer "B.Cu")
		(at 107.893 159.355571 180)
		(descr "Capacitor SMD 0402")
		(tags "capacitor SMD 0402")
		(property "Reference" "C139"
			(at -3.707 -0.004429 0)
			(layer "B.SilkS")
			(effects
				(font
					(size 0.7 0.7)
					(thickness 0.15)
				)
				(justify left bottom mirror)
			)
		)
		(property "Value" "C_220n_0402"
			(at -1.022927 -2.155213 0)
			(layer "B.Fab")
			(effects
				(font
					(size 0.7 0.7)
					(thickness 0.15)
				)
				(justify left bottom mirror)
			)
		)
		(property "Datasheet" "https://www.yageo.com/en/Chart/Download/pdf/CC0402KRX5R6BB224"
			(at 0 0 180)
			(layer "F.Fab")
			(hide yes)
			(effects
				(font
					(size 1.27 1.27)
					(thickness 0.15)
				)
			)
		)
		(property "Author" "Antmicro"
			(at 215.786 318.711142 0)
			(layer "B.Fab")
			(hide yes)
			(effects
				(font
					(size 1 1)
					(thickness 0.15)
				)
				(justify mirror)
			)
		)
		(property "Dielectric" ""
			(at 215.786 318.711142 0)
			(layer "B.Fab")
			(hide yes)
			(effects
				(font
					(size 1 1)
					(thickness 0.15)
				)
				(justify mirror)
			)
		)
		(property "License" "Apache-2.0"
			(at 215.786 318.711142 0)
			(layer "B.Fab")
			(hide yes)
			(effects
				(font
					(size 1 1)
					(thickness 0.15)
				)
				(justify mirror)
			)
		)
		(property "MPN" "CC0402KRX5R6BB224"
			(at 215.786 318.711142 0)
			(layer "B.Fab")
			(hide yes)
			(effects
				(font
					(size 1 1)
					(thickness 0.15)
				)
				(justify mirror)
			)
		)
		(property "Manufacturer" "YAGEO"
			(at 215.786 318.711142 0)
			(layer "B.Fab")
			(hide yes)
			(effects
				(font
					(size 1 1)
					(thickness 0.15)
				)
				(justify mirror)
			)
		)
		(property "Public" "False"
			(at 215.786 318.711142 0)
			(layer "B.Fab")
			(hide yes)
			(effects
				(font
					(size 1 1)
					(thickness 0.15)
				)
				(justify mirror)
			)
		)
		(property "Val" "220n"
			(at 215.786 318.711142 0)
			(layer "B.Fab")
			(hide yes)
			(effects
				(font
					(size 1 1)
					(thickness 0.15)
				)
				(justify mirror)
			)
		)
		(property "Voltage" ""
			(at 215.786 318.711142 0)
			(layer "B.Fab")
			(hide yes)
			(effects
				(font
					(size 1 1)
					(thickness 0.15)
				)
				(justify mirror)
			)
		)
		(sheetname "PCIe redriver")
		(sheetfile "pcie_redriver.kicad_sch")
		(attr smd)
		(fp_rect
			(start -0.925 0.47)
			(end 0.925 -0.47)
			(stroke
				(width 0.05)
				(type default)
			)
			(fill no)
			(layer "B.CrtYd")
		)
		(fp_line
			(start 0.504 0.25)
			(end -0.494 0.25)
			(stroke
				(width 0.15)
				(type solid)
			)
			(layer "B.Fab")
		)
		(fp_line
			(start 0.504 -0.248)
			(end 0.504 0.25)
			(stroke
				(width 0.15)
				(type solid)
			)
			(layer "B.Fab")
		)
		(fp_line
			(start -0.494 0.25)
			(end -0.494 -0.248)
			(stroke
				(width 0.15)
				(type solid)
			)
			(layer "B.Fab")
		)
		(fp_line
			(start -0.494 -0.248)
			(end 0.504 -0.248)
			(stroke
				(width 0.15)
				(type solid)
			)
			(layer "B.Fab")
		)
		(pad "1" smd roundrect
			(at -0.48 0 180)
			(size 0.59 0.64)
			(layers "B.Cu" "B.Mask" "B.Paste")
			(roundrect_rratio 0.25)
			(net 94 "/PCIe redriver/PCIe_{O}_C.TX3+")
			(pintype "passive")
			(teardrops
				(best_length_ratio 0.2)
				(max_length 1)
				(best_width_ratio 0.9)
				(max_width 2)
				(curved_edges yes)
				(filter_ratio 0.9)
				(enabled yes)
				(allow_two_segments yes)
				(prefer_zone_connections yes)
			)
		)
		(pad "2" smd roundrect
			(at 0.48 0 180)
			(size 0.59 0.64)
			(layers "B.Cu" "B.Mask" "B.Paste")
			(roundrect_rratio 0.25)
			(net 106 "/OCuLink/PCIe_{x4}.TX3+")
			(pintype "passive")
			(teardrops
				(best_length_ratio 0.2)
				(max_length 1)
				(best_width_ratio 0.9)
				(max_width 2)
				(curved_edges yes)
				(filter_ratio 0.9)
				(enabled yes)
				(allow_two_segments yes)
				(prefer_zone_connections yes)
			)
		)
	)
)
